# T6G (Grand Teton) — schematic netlist excerpt (pin names and nets, part order shuffled) for the footprints in the layout excerpt that follows; sources: Cadence DE-HDL packaged netlist, KiCad conversion of 04192023_DAF0TMB3IC0_F0TG_MB_C_brd_V02_OCP.brd

R1165  Q_RES  1K 1% CHIP  pkg 0402LF  page 142 : A = P3V3_AUX ; B = P12V_OCP_V3_2_EN_R3
PC624_3  Q_CAP  1UF 25V 10% X6S  pkg C0402  page 223 : A = SW_P12V_AUX_PVDDIO_P1_FLT ; B = GND

(kicad_pcb
	(version 20260206)
	(generator "pcbnew")
	(generator_version "10.0")
	(general
		(thickness 1.6)
		(legacy_teardrops no)
	)
	(paper "A4")
	(title_block
		(title "04192023_DAF0TMB3IC0_F0TG_MB_C_brd_V02_OCP.brd")
		(comment 1 "Grand Teton / footprints 214-215 of 8354")
	)
	(layers
		(0 "F.Cu" signal "TOP")
		(4 "In1.Cu" signal "GND")
		(6 "In2.Cu" signal "IN1")
		(8 "In3.Cu" signal "GND1")
		(10 "In4.Cu" signal "IN2")
		(12 "In5.Cu" signal "GND2")
		(14 "In6.Cu" signal "IN3")
		(16 "In7.Cu" signal "GND3")
		(18 "In8.Cu" signal "VCC")
		(20 "In9.Cu" signal "VCC1")
		(22 "In10.Cu" signal "GND4")
		(24 "In11.Cu" signal "IN4")
		(26 "In12.Cu" signal "GND5")
		(28 "In13.Cu" signal "IN5")
		(30 "In14.Cu" signal "GND6")
		(32 "In15.Cu" signal "IN6")
		(34 "In16.Cu" signal "GND7")
		(2 "B.Cu" signal "BOTTOM")
		(9 "F.Adhes" user "F.Adhesive")
		(11 "B.Adhes" user "B.Adhesive")
		(13 "F.Paste" user "Package Geometry/Pastemask Top")
		(15 "B.Paste" user "Package Geometry/Pastemask Bottom")
		(5 "F.SilkS" user "Ref Des/Silkscreen Top")
		(7 "B.SilkS" user "Ref Des/Silkscreen Bottom")
		(1 "F.Mask" user "Board Geometry/Soldermask Top")
		(3 "B.Mask" user "Board Geometry/Soldermask Bottom")
		(17 "Dwgs.User" user "User.Drawings")
		(19 "Cmts.User" user "User.Comments")
		(21 "Eco1.User" user "User.Eco1")
		(23 "Eco2.User" user "User.Eco2")
		(25 "Edge.Cuts" user "Board Geometry/Outline")
		(27 "Margin" user)
		(31 "F.CrtYd" user "Package Geometry/Place Bound Top")
		(29 "B.CrtYd" user "Package Geometry/Place Bound Bottom")
		(35 "F.Fab" user "Ref Des/Assembly Top")
		(33 "B.Fab" user "Ref Des/Assembly Bottom")
	)
	(footprint ""
		(layer "F.Cu")
		(at 40.51554 -346.813632 -90)
		(property "Reference" "PC624_3"
			(at 0 0 270)
			(layer "F.SilkS")
			(hide yes)
			(effects
				(font
					(size 1.27 1.27)
				)
			)
		)
		(property "Value" ""
			(at 0 0 270)
			(layer "F.Fab")
			(effects
				(font
					(size 1.27 1.27)
				)
			)
		)
		(duplicate_pad_numbers_are_jumpers no)
		(fp_line
			(start -0.7874 0.4064)
			(end -0.7874 -0.4064)
			(stroke
				(width 0.1524)
				(type default)
			)
			(layer "F.SilkS")
		)
		(fp_line
			(start 0.7874 0.4064)
			(end -0.7874 0.4064)
			(stroke
				(width 0.1524)
				(type default)
			)
			(layer "F.SilkS")
		)
		(fp_line
			(start -0.7874 -0.4064)
			(end 0.7874 -0.4064)
			(stroke
				(width 0.1524)
				(type default)
			)
			(layer "F.SilkS")
		)
		(fp_line
			(start 0.7874 -0.4064)
			(end 0.7874 0.4064)
			(stroke
				(width 0.1524)
				(type default)
			)
			(layer "F.SilkS")
		)
		(fp_line
			(start -0.67945 0.3048)
			(end -0.67945 -0.305054)
			(stroke
				(width 0.1)
				(type default)
			)
			(layer "F.Fab")
		)
		(fp_line
			(start -0.12065 0.3048)
			(end -0.67945 0.3048)
			(stroke
				(width 0.1)
				(type default)
			)
			(layer "F.Fab")
		)
		(fp_line
			(start 0.120396 0.3048)
			(end 0.120396 0.2794)
			(stroke
				(width 0.1)
				(type default)
			)
			(layer "F.Fab")
		)
		(fp_line
			(start 0.67945 0.3048)
			(end 0.120396 0.3048)
			(stroke
				(width 0.1)
				(type default)
			)
			(layer "F.Fab")
		)
		(fp_line
			(start -0.12065 0.2794)
			(end -0.12065 0.3048)
			(stroke
				(width 0.1)
				(type default)
			)
			(layer "F.Fab")
		)
		(fp_line
			(start 0.120396 0.2794)
			(end -0.12065 0.2794)
			(stroke
				(width 0.1)
				(type default)
			)
			(layer "F.Fab")
		)
		(fp_line
			(start -0.12065 -0.2794)
			(end 0.12065 -0.2794)
			(stroke
				(width 0.1)
				(type default)
			)
			(layer "F.Fab")
		)
		(fp_line
			(start 0.12065 -0.2794)
			(end 0.12065 -0.3048)
			(stroke
				(width 0.1)
				(type default)
			)
			(layer "F.Fab")
		)
		(fp_line
			(start 0.12065 -0.3048)
			(end 0.67945 -0.3048)
			(stroke
				(width 0.1)
				(type default)
			)
			(layer "F.Fab")
		)
		(fp_line
			(start 0.67945 -0.3048)
			(end 0.67945 0.3048)
			(stroke
				(width 0.1)
				(type default)
			)
			(layer "F.Fab")
		)
		(fp_line
			(start -0.67945 -0.305054)
			(end -0.12065 -0.305054)
			(stroke
				(width 0.1)
				(type default)
			)
			(layer "F.Fab")
		)
		(fp_line
			(start -0.12065 -0.305054)
			(end -0.12065 -0.2794)
			(stroke
				(width 0.1)
				(type default)
			)
			(layer "F.Fab")
		)
		(pad "1" smd circle
			(at -0.40005 0 270)
			(size 0 0)
			(layers "F.Cu" "F.Mask" "F.Paste")
			(net "SW_P12V_AUX_PVDDIO_P1_FLT")
		)
		(pad "2" smd circle
			(at 0.40005 0 270)
			(size 0 0)
			(layers "F.Cu" "F.Mask" "F.Paste")
			(net "GND")
		)
	)
	(footprint ""
		(layer "F.Cu")
		(at 49.784 -39.751)
		(property "Reference" "R1165"
			(at 0 0 0)
			(layer "F.SilkS")
			(hide yes)
			(effects
				(font
					(size 1.27 1.27)
				)
			)
		)
		(property "Value" ""
			(at 0 0 0)
			(layer "F.Fab")
			(effects
				(font
					(size 1.27 1.27)
				)
			)
		)
		(duplicate_pad_numbers_are_jumpers no)
		(fp_line
			(start -0.7874 -0.4064)
			(end 0.7874 -0.4064)
			(stroke
				(width 0.1524)
				(type default)
			)
			(layer "F.SilkS")
		)
		(fp_line
			(start -0.7874 0.4064)
			(end -0.7874 -0.4064)
			(stroke
				(width 0.1524)
				(type default)
			)
			(layer "F.SilkS")
		)
		(fp_line
			(start 0.7874 -0.4064)
			(end 0.7874 0.4064)
			(stroke
				(width 0.1524)
				(type default)
			)
			(layer "F.SilkS")
		)
		(fp_line
			(start 0.7874 0.4064)
			(end -0.7874 0.4064)
			(stroke
				(width 0.1524)
				(type default)
			)
			(layer "F.SilkS")
		)
		(fp_line
			(start -0.67945 -0.305054)
			(end -0.12065 -0.305054)
			(stroke
				(width 0.1)
				(type default)
			)
			(layer "F.Fab")
		)
		(fp_line
			(start -0.67945 0.3048)
			(end -0.67945 -0.305054)
			(stroke
				(width 0.1)
				(type default)
			)
			(layer "F.Fab")
		)
		(fp_line
			(start -0.12065 -0.305054)
			(end -0.12065 -0.2794)
			(stroke
				(width 0.1)
				(type default)
			)
			(layer "F.Fab")
		)
		(fp_line
			(start -0.12065 -0.2794)
			(end 0.12065 -0.2794)
			(stroke
				(width 0.1)
				(type default)
			)
			(layer "F.Fab")
		)
		(fp_line
			(start -0.12065 0.2794)
			(end -0.12065 0.3048)
			(stroke
				(width 0.1)
				(type default)
			)
			(layer "F.Fab")
		)
		(fp_line
			(start -0.12065 0.3048)
			(end -0.67945 0.3048)
			(stroke
				(width 0.1)
				(type default)
			)
			(layer "F.Fab")
		)
		(fp_line
			(start 0.120396 0.2794)
			(end -0.12065 0.2794)
			(stroke
				(width 0.1)
				(type default)
			)
			(layer "F.Fab")
		)
		(fp_line
			(start 0.120396 0.3048)
			(end 0.120396 0.2794)
			(stroke
				(width 0.1)
				(type default)
			)
			(layer "F.Fab")
		)
		(fp_line
			(start 0.12065 -0.3048)
			(end 0.67945 -0.3048)
			(stroke
				(width 0.1)
				(type default)
			)
			(layer "F.Fab")
		)
		(fp_line
			(start 0.12065 -0.2794)
			(end 0.12065 -0.3048)
			(stroke
				(width 0.1)
				(type default)
			)
			(layer "F.Fab")
		)
		(fp_line
			(start 0.67945 -0.3048)
			(end 0.67945 0.3048)
			(stroke
				(width 0.1)
				(type default)
			)
			(layer "F.Fab")
		)
		(fp_line
			(start 0.67945 0.3048)
			(end 0.120396 0.3048)
			(stroke
				(width 0.1)
				(type default)
			)
			(layer "F.Fab")
		)
		(pad "1" smd circle
			(at -0.40005 0)
			(size 0 0)
			(layers "F.Cu" "F.Mask" "F.Paste")
			(net "P3V3_AUX")
		)
		(pad "2" smd circle
			(at 0.40005 0)
			(size 0 0)
			(layers "F.Cu" "F.Mask" "F.Paste")
			(net "P12V_OCP_V3_2_EN_R3")
		)
	)
)
